(kicad_pcb
	(version 20260206)
	(generator "pcbnew")
	(generator_version "10.0")
	(general
		(thickness 1.6)
		(legacy_teardrops no)
	)
	(paper "A4")
	(title_block
		(title "01162023_DA0F0TEBIF0_F0T_Expander_BD_F_brd_V02_OCP.brd")
		(comment 1 "Grand Teton / footprints 6363-6363 of 9728")
	)
	(layers
		(0 "F.Cu" signal "TOP")
		(4 "In1.Cu" signal "GND")
		(6 "In2.Cu" signal "VCC")
		(8 "In3.Cu" signal "VCC1")
		(10 "In4.Cu" signal "GND1")
		(12 "In5.Cu" signal "IN1")
		(14 "In6.Cu" signal "GND2")
		(16 "In7.Cu" signal "IN2")
		(18 "In8.Cu" signal "GND3")
		(20 "In9.Cu" signal "IN3")
		(22 "In10.Cu" signal "GND4")
		(24 "In11.Cu" signal "IN4")
		(26 "In12.Cu" signal "GND5")
		(28 "In13.Cu" signal "IN5")
		(30 "In14.Cu" signal "GND6")
		(32 "In15.Cu" signal "IN6")
		(34 "In16.Cu" signal "GND7")
		(2 "B.Cu" signal "BOTTOM")
		(9 "F.Adhes" user "F.Adhesive")
		(11 "B.Adhes" user "B.Adhesive")
		(13 "F.Paste" user "Package Geometry/Pastemask Top")
		(15 "B.Paste" user "Package Geometry/Pastemask Bottom")
		(5 "F.SilkS" user "Ref Des/Silkscreen Top")
		(7 "B.SilkS" user "Ref Des/Silkscreen Bottom")
		(1 "F.Mask" user "Board Geometry/Soldermask Top")
		(3 "B.Mask" user "Board Geometry/Soldermask Bottom")
		(17 "Dwgs.User" user "User.Drawings")
		(19 "Cmts.User" user "User.Comments")
		(21 "Eco1.User" user "User.Eco1")
		(23 "Eco2.User" user "User.Eco2")
		(25 "Edge.Cuts" user "Board Geometry/Outline")
		(27 "Margin" user)
		(31 "F.CrtYd" user "Package Geometry/Place Bound Top")
		(29 "B.CrtYd" user "Package Geometry/Place Bound Bottom")
		(35 "F.Fab" user "Ref Des/Assembly Top")
		(33 "B.Fab" user "Ref Des/Assembly Bottom")
	)
	(footprint ""
		(layer "F.Cu")
		(at 124.272548 -343.952322 90)
		(property "Reference" "C350"
			(at 0 0 90)
			(layer "F.SilkS")
			(hide yes)
			(effects
				(font
					(size 1.27 1.27)
				)
			)
		)
		(property "Value" ""
			(at 0 0 90)
			(layer "F.Fab")
			(effects
				(font
					(size 1.27 1.27)
				)
			)
		)
		(duplicate_pad_numbers_are_jumpers no)
		(fp_line
			(start 0.299974 -0.150114)
			(end 0.299974 0.150114)
			(stroke
				(width 0.1)
				(type default)
			)
			(layer "F.Fab")
		)
		(fp_line
			(start -0.299974 -0.150114)
			(end 0.299974 -0.150114)
			(stroke
				(width 0.1)
				(type default)
			)
			(layer "F.Fab")
		)
		(fp_line
			(start 0.299974 0.150114)
			(end -0.299974 0.150114)
			(stroke
				(width 0.1)
				(type default)
			)
			(layer "F.Fab")
		)
		(fp_line
			(start -0.299974 0.150114)
			(end -0.299974 -0.150114)
			(stroke
				(width 0.1)
				(type default)
			)
			(layer "F.Fab")
		)
		(pad "1" smd rect
			(at -0.2667 0 90)
			(size 0.3048 0.381)
			(layers "F.Cu" "F.Mask" "F.Paste")
			(net "P5E_PEX1_STN6_TX_DP<106>")
		)
		(pad "2" smd rect
			(at 0.2667 0 90)
			(size 0.3048 0.381)
			(layers "F.Cu" "F.Mask" "F.Paste")
			(net "P5E_PEX1_STN6_TX_C_DP<106>")
		)
	)
)
